FILE_TYPE = CONNECTIVITY;
{Allegro Design Entry HDL 16.6-p007 (v16-6-112F) 10/10/2012}
"PAGE_NUMBER" = 33;
0"NC";
1"UPI_CPU0_CPU1_P0P0_DN<19..0>";
2"UPI_CPU0_CPU1_P0P0_DP<19..0>";
3"UPI_CPU1_CPU0_P0P0_DN<19..0>";
4"UPI_CPU1_CPU0_P0P0_DP<19..0>";
5"UPI_CPU1_CPU0_P0P0_DN<19>";
6"UPI_CPU1_CPU0_P0P0_DN<18>";
7"UPI_CPU1_CPU0_P0P0_DN<17>";
8"UPI_CPU1_CPU0_P0P0_DN<16>";
9"UPI_CPU1_CPU0_P0P0_DN<15>";
10"UPI_CPU1_CPU0_P0P0_DN<14>";
11"UPI_CPU1_CPU0_P0P0_DN<13>";
12"UPI_CPU1_CPU0_P0P0_DN<12>";
13"UPI_CPU1_CPU0_P0P0_DN<11>";
14"UPI_CPU1_CPU0_P0P0_DP<19>";
15"UPI_CPU1_CPU0_P0P0_DP<18>";
16"UPI_CPU1_CPU0_P0P0_DP<17>";
17"UPI_CPU1_CPU0_P0P0_DP<16>";
18"UPI_CPU1_CPU0_P0P0_DP<15>";
19"UPI_CPU1_CPU0_P0P0_DP<14>";
20"UPI_CPU1_CPU0_P0P0_DP<13>";
21"UPI_CPU1_CPU0_P0P0_DP<12>";
22"UPI_CPU1_CPU0_P0P0_DP<11>";
23"UPI_CPU1_CPU0_P0P0_DP<10>";
24"UPI_CPU1_CPU0_P0P0_DP<9>";
25"UPI_CPU1_CPU0_P0P0_DP<8>";
26"UPI_CPU1_CPU0_P0P0_DP<7>";
27"UPI_CPU1_CPU0_P0P0_DP<6>";
28"UPI_CPU1_CPU0_P0P0_DP<5>";
29"UPI_CPU1_CPU0_P0P0_DP<4>";
30"UPI_CPU1_CPU0_P0P0_DP<3>";
31"UPI_CPU1_CPU0_P0P0_DP<2>";
32"UPI_CPU1_CPU0_P0P0_DP<1>";
33"UPI_CPU1_CPU0_P0P0_DP<0>";
34"UPI_CPU1_CPU0_P0P0_DN<10>";
35"UPI_CPU1_CPU0_P0P0_DN<9>";
36"UPI_CPU1_CPU0_P0P0_DN<8>";
37"UPI_CPU1_CPU0_P0P0_DN<7>";
38"UPI_CPU1_CPU0_P0P0_DN<6>";
39"UPI_CPU1_CPU0_P0P0_DN<5>";
40"UPI_CPU1_CPU0_P0P0_DN<4>";
41"UPI_CPU1_CPU0_P0P0_DN<3>";
42"UPI_CPU1_CPU0_P0P0_DN<2>";
43"UPI_CPU1_CPU0_P0P0_DN<1>";
44"UPI_CPU1_CPU0_P0P0_DN<0>";
45"UPI_CPU0_CPU1_P0P0_DN<19>";
46"UPI_CPU0_CPU1_P0P0_DN<18>";
47"UPI_CPU0_CPU1_P0P0_DN<17>";
48"UPI_CPU0_CPU1_P0P0_DN<16>";
49"UPI_CPU0_CPU1_P0P0_DN<15>";
50"UPI_CPU0_CPU1_P0P0_DN<14>";
51"UPI_CPU0_CPU1_P0P0_DN<13>";
52"UPI_CPU0_CPU1_P0P0_DN<12>";
53"UPI_CPU0_CPU1_P0P0_DN<11>";
54"UPI_CPU0_CPU1_P0P0_DP<19>";
55"UPI_CPU0_CPU1_P0P0_DP<18>";
56"UPI_CPU0_CPU1_P0P0_DP<17>";
57"UPI_CPU0_CPU1_P0P0_DP<16>";
58"UPI_CPU0_CPU1_P0P0_DP<15>";
59"UPI_CPU0_CPU1_P0P0_DP<14>";
60"UPI_CPU0_CPU1_P0P0_DP<13>";
61"UPI_CPU0_CPU1_P0P0_DP<12>";
62"UPI_CPU0_CPU1_P0P0_DP<11>";
63"UPI_CPU0_CPU1_P0P0_DP<10>";
64"UPI_CPU0_CPU1_P0P0_DP<9>";
65"UPI_CPU0_CPU1_P0P0_DP<8>";
66"UPI_CPU0_CPU1_P0P0_DP<7>";
67"UPI_CPU0_CPU1_P0P0_DP<6>";
68"UPI_CPU0_CPU1_P0P0_DP<5>";
69"UPI_CPU0_CPU1_P0P0_DP<4>";
70"UPI_CPU0_CPU1_P0P0_DP<3>";
71"UPI_CPU0_CPU1_P0P0_DP<2>";
72"UPI_CPU0_CPU1_P0P0_DP<1>";
73"UPI_CPU0_CPU1_P0P0_DP<0>";
74"UPI_CPU0_CPU1_P0P0_DN<10>";
75"UPI_CPU0_CPU1_P0P0_DN<9>";
76"UPI_CPU0_CPU1_P0P0_DN<8>";
77"UPI_CPU0_CPU1_P0P0_DN<7>";
78"UPI_CPU0_CPU1_P0P0_DN<6>";
79"UPI_CPU0_CPU1_P0P0_DN<5>";
80"UPI_CPU0_CPU1_P0P0_DN<4>";
81"UPI_CPU0_CPU1_P0P0_DN<3>";
82"UPI_CPU0_CPU1_P0P0_DN<2>";
83"UPI_CPU0_CPU1_P0P0_DN<1>";
84"UPI_CPU0_CPU1_P0P0_DN<0>";
%"TAP"
"1","(-5250,1900)","2","mstr_standard","I10";
;
HDL_TAP"TRUE"
BODY_TYPE"PLUMBING"
CDS_LIB"mstr_standard";
"B \NAC \NWC"3;
"S \NAC"
BN"13"11;
%"TAP"
"1","(-5250,2000)","2","mstr_standard","I11";
;
HDL_TAP"TRUE"
BODY_TYPE"PLUMBING"
CDS_LIB"mstr_standard";
"B \NAC \NWC"3;
"S \NAC"
BN"11"13;
%"TAP"
"1","(-5250,2100)","2","mstr_standard","I13";
;
HDL_TAP"TRUE"
BODY_TYPE"PLUMBING"
CDS_LIB"mstr_standard";
"B \NAC \NWC"3;
"S \NAC"
BN"9"35;
%"TAP"
"1","(-5250,2050)","2","mstr_standard","I14";
;
HDL_TAP"TRUE"
BODY_TYPE"PLUMBING"
CDS_LIB"mstr_standard";
"B \NAC \NWC"3;
"S \NAC"
BN"10"34;
%"TAP"
"1","(-5250,2250)","2","mstr_standard","I15";
;
HDL_TAP"TRUE"
BODY_TYPE"PLUMBING"
CDS_LIB"mstr_standard";
"B \NAC \NWC"3;
"S \NAC"
BN"6"38;
%"TAP"
"1","(-5250,2200)","2","mstr_standard","I16";
;
HDL_TAP"TRUE"
BODY_TYPE"PLUMBING"
CDS_LIB"mstr_standard";
"B \NAC \NWC"3;
"S \NAC"
BN"7"37;
%"TAP"
"1","(-5250,2150)","2","mstr_standard","I17";
;
HDL_TAP"TRUE"
BODY_TYPE"PLUMBING"
CDS_LIB"mstr_standard";
"B \NAC \NWC"3;
"S \NAC"
BN"8"36;
%"TAP"
"1","(-5250,2350)","2","mstr_standard","I18";
;
HDL_TAP"TRUE"
BODY_TYPE"PLUMBING"
CDS_LIB"mstr_standard";
"B \NAC \NWC"3;
"S \NAC"
BN"4"40;
%"TAP"
"1","(-5250,2300)","2","mstr_standard","I19";
;
HDL_TAP"TRUE"
BODY_TYPE"PLUMBING"
CDS_LIB"mstr_standard";
"B \NAC \NWC"3;
"S \NAC"
BN"5"39;
%"TAP"
"1","(-5250,2500)","2","mstr_standard","I20";
;
HDL_TAP"TRUE"
BODY_TYPE"PLUMBING"
CDS_LIB"mstr_standard";
"B \NAC \NWC"3;
"S \NAC"
BN"1"43;
%"TAP"
"1","(-5250,2450)","2","mstr_standard","I21";
;
HDL_TAP"TRUE"
BODY_TYPE"PLUMBING"
CDS_LIB"mstr_standard";
"B \NAC \NWC"3;
"S \NAC"
BN"2"42;
%"TAP"
"1","(-5250,2400)","2","mstr_standard","I22";
;
HDL_TAP"TRUE"
BODY_TYPE"PLUMBING"
CDS_LIB"mstr_standard";
"B \NAC \NWC"3;
"S \NAC"
BN"3"41;
%"TAP"
"1","(-5250,2750)","2","mstr_standard","I23";
;
HDL_TAP"TRUE"
BODY_TYPE"PLUMBING"
CDS_LIB"mstr_standard";
"B \NAC \NWC"4;
"S \NAC"
BN"17"16;
%"TAP"
"1","(-5250,2650)","2","mstr_standard","I24";
;
HDL_TAP"TRUE"
BODY_TYPE"PLUMBING"
CDS_LIB"mstr_standard";
"B \NAC \NWC"4;
"S \NAC"
BN"19"14;
%"TAP"
"1","(-5250,2700)","2","mstr_standard","I25";
;
HDL_TAP"TRUE"
BODY_TYPE"PLUMBING"
CDS_LIB"mstr_standard";
"B \NAC \NWC"4;
"S \NAC"
BN"18"15;
%"TAP"
"1","(-5250,2550)","2","mstr_standard","I26";
;
HDL_TAP"TRUE"
BODY_TYPE"PLUMBING"
CDS_LIB"mstr_standard";
"B \NAC \NWC"3;
"S \NAC"
BN"0"44;
%"TAP"
"1","(-5250,2850)","2","mstr_standard","I27";
;
HDL_TAP"TRUE"
BODY_TYPE"PLUMBING"
CDS_LIB"mstr_standard";
"B \NAC \NWC"4;
"S \NAC"
BN"15"18;
%"TAP"
"1","(-5250,2800)","2","mstr_standard","I28";
;
HDL_TAP"TRUE"
BODY_TYPE"PLUMBING"
CDS_LIB"mstr_standard";
"B \NAC \NWC"4;
"S \NAC"
BN"16"17;
%"TAP"
"1","(-5250,2950)","2","mstr_standard","I29";
;
HDL_TAP"TRUE"
BODY_TYPE"PLUMBING"
CDS_LIB"mstr_standard";
"B \NAC \NWC"4;
"S \NAC"
BN"13"20;
%"TAP"
"1","(-5250,1600)","2","mstr_standard","I3";
;
HDL_TAP"TRUE"
BODY_TYPE"PLUMBING"
CDS_LIB"mstr_standard";
"B \NAC \NWC"3;
"S \NAC"
BN"19"5;
%"TAP"
"1","(-5250,3000)","2","mstr_standard","I30";
;
HDL_TAP"TRUE"
BODY_TYPE"PLUMBING"
CDS_LIB"mstr_standard";
"B \NAC \NWC"4;
"S \NAC"
BN"12"21;
%"TAP"
"1","(-5250,2900)","2","mstr_standard","I31";
;
HDL_TAP"TRUE"
BODY_TYPE"PLUMBING"
CDS_LIB"mstr_standard";
"B \NAC \NWC"4;
"S \NAC"
BN"14"19;
%"TAP"
"1","(-5250,3050)","2","mstr_standard","I32";
;
HDL_TAP"TRUE"
BODY_TYPE"PLUMBING"
CDS_LIB"mstr_standard";
"B \NAC \NWC"4;
"S \NAC"
BN"11"22;
%"TAP"
"1","(-5250,3100)","2","mstr_standard","I33";
;
HDL_TAP"TRUE"
BODY_TYPE"PLUMBING"
CDS_LIB"mstr_standard";
"B \NAC \NWC"4;
"S \NAC"
BN"10"23;
%"TAP"
"1","(-5250,3150)","2","mstr_standard","I34";
;
HDL_TAP"TRUE"
BODY_TYPE"PLUMBING"
CDS_LIB"mstr_standard";
"B \NAC \NWC"4;
"S \NAC"
BN"9"24;
%"TAP"
"1","(-5250,3250)","2","mstr_standard","I35";
;
HDL_TAP"TRUE"
BODY_TYPE"PLUMBING"
CDS_LIB"mstr_standard";
"B \NAC \NWC"4;
"S \NAC"
BN"7"26;
%"TAP"
"1","(-5250,3200)","2","mstr_standard","I36";
;
HDL_TAP"TRUE"
BODY_TYPE"PLUMBING"
CDS_LIB"mstr_standard";
"B \NAC \NWC"4;
"S \NAC"
BN"8"25;
%"TAP"
"1","(-5250,3300)","2","mstr_standard","I37";
;
HDL_TAP"TRUE"
BODY_TYPE"PLUMBING"
CDS_LIB"mstr_standard";
"B \NAC \NWC"4;
"S \NAC"
BN"6"27;
%"TAP"
"1","(-5250,3400)","2","mstr_standard","I38";
;
HDL_TAP"TRUE"
BODY_TYPE"PLUMBING"
CDS_LIB"mstr_standard";
"B \NAC \NWC"4;
"S \NAC"
BN"4"29;
%"TAP"
"1","(-5250,3350)","2","mstr_standard","I39";
;
HDL_TAP"TRUE"
BODY_TYPE"PLUMBING"
CDS_LIB"mstr_standard";
"B \NAC \NWC"4;
"S \NAC"
BN"5"28;
%"TAP"
"1","(-5250,1700)","2","mstr_standard","I4";
;
HDL_TAP"TRUE"
BODY_TYPE"PLUMBING"
CDS_LIB"mstr_standard";
"B \NAC \NWC"3;
"S \NAC"
BN"17"7;
%"TAP"
"1","(-5250,3500)","2","mstr_standard","I40";
;
HDL_TAP"TRUE"
BODY_TYPE"PLUMBING"
CDS_LIB"mstr_standard";
"B \NAC \NWC"4;
"S \NAC"
BN"2"31;
%"TAP"
"1","(-5250,3450)","2","mstr_standard","I41";
;
HDL_TAP"TRUE"
BODY_TYPE"PLUMBING"
CDS_LIB"mstr_standard";
"B \NAC \NWC"4;
"S \NAC"
BN"3"30;
%"TAP"
"1","(-5250,3550)","2","mstr_standard","I42";
;
HDL_TAP"TRUE"
BODY_TYPE"PLUMBING"
CDS_LIB"mstr_standard";
"B \NAC \NWC"4;
"S \NAC"
BN"1"32;
%"TAP"
"1","(-5250,3600)","2","mstr_standard","I43";
;
HDL_TAP"TRUE"
BODY_TYPE"PLUMBING"
CDS_LIB"mstr_standard";
"B \NAC \NWC"4;
"S \NAC"
BN"0"33;
%"TAP"
"1","(-2925,1600)","0","mstr_standard","I44";
;
HDL_TAP"TRUE"
BODY_TYPE"PLUMBING"
CDS_LIB"mstr_standard";
"B \NAC \NWC"1;
"S \NAC"
BN"19"45;
%"TAP"
"1","(-2925,1750)","0","mstr_standard","I45";
;
HDL_TAP"TRUE"
BODY_TYPE"PLUMBING"
CDS_LIB"mstr_standard";
"B \NAC \NWC"1;
"S \NAC"
BN"16"48;
%"TAP"
"1","(-2925,1700)","0","mstr_standard","I46";
;
HDL_TAP"TRUE"
BODY_TYPE"PLUMBING"
CDS_LIB"mstr_standard";
"B \NAC \NWC"1;
"S \NAC"
BN"17"47;
%"TAP"
"1","(-2925,1650)","0","mstr_standard","I47";
;
HDL_TAP"TRUE"
BODY_TYPE"PLUMBING"
CDS_LIB"mstr_standard";
"B \NAC \NWC"1;
"S \NAC"
BN"18"46;
%"TAP"
"1","(-2925,1850)","0","mstr_standard","I48";
;
HDL_TAP"TRUE"
BODY_TYPE"PLUMBING"
CDS_LIB"mstr_standard";
"B \NAC \NWC"1;
"S \NAC"
BN"14"50;
%"TAP"
"1","(-2925,1800)","0","mstr_standard","I49";
;
HDL_TAP"TRUE"
BODY_TYPE"PLUMBING"
CDS_LIB"mstr_standard";
"B \NAC \NWC"1;
"S \NAC"
BN"15"49;
%"TAP"
"1","(-5250,1650)","2","mstr_standard","I5";
;
HDL_TAP"TRUE"
BODY_TYPE"PLUMBING"
CDS_LIB"mstr_standard";
"B \NAC \NWC"3;
"S \NAC"
BN"18"6;
%"TAP"
"1","(-2925,1900)","0","mstr_standard","I50";
;
HDL_TAP"TRUE"
BODY_TYPE"PLUMBING"
CDS_LIB"mstr_standard";
"B \NAC \NWC"1;
"S \NAC"
BN"13"51;
%"TAP"
"1","(-2925,2000)","0","mstr_standard","I51";
;
HDL_TAP"TRUE"
BODY_TYPE"PLUMBING"
CDS_LIB"mstr_standard";
"B \NAC \NWC"1;
"S \NAC"
BN"11"53;
%"TAP"
"1","(-2925,1950)","0","mstr_standard","I52";
;
HDL_TAP"TRUE"
BODY_TYPE"PLUMBING"
CDS_LIB"mstr_standard";
"B \NAC \NWC"1;
"S \NAC"
BN"12"52;
%"TAP"
"1","(-2925,2150)","0","mstr_standard","I53";
;
HDL_TAP"TRUE"
BODY_TYPE"PLUMBING"
CDS_LIB"mstr_standard";
"B \NAC \NWC"1;
"S \NAC"
BN"8"76;
%"TAP"
"1","(-2925,2100)","0","mstr_standard","I54";
;
HDL_TAP"TRUE"
BODY_TYPE"PLUMBING"
CDS_LIB"mstr_standard";
"B \NAC \NWC"1;
"S \NAC"
BN"9"75;
%"TAP"
"1","(-2925,2050)","0","mstr_standard","I55";
;
HDL_TAP"TRUE"
BODY_TYPE"PLUMBING"
CDS_LIB"mstr_standard";
"B \NAC \NWC"1;
"S \NAC"
BN"10"74;
%"TAP"
"1","(-2925,2250)","0","mstr_standard","I56";
;
HDL_TAP"TRUE"
BODY_TYPE"PLUMBING"
CDS_LIB"mstr_standard";
"B \NAC \NWC"1;
"S \NAC"
BN"6"78;
%"TAP"
"1","(-2925,2200)","0","mstr_standard","I57";
;
HDL_TAP"TRUE"
BODY_TYPE"PLUMBING"
CDS_LIB"mstr_standard";
"B \NAC \NWC"1;
"S \NAC"
BN"7"77;
%"TAP"
"1","(-2925,2300)","0","mstr_standard","I58";
;
HDL_TAP"TRUE"
BODY_TYPE"PLUMBING"
CDS_LIB"mstr_standard";
"B \NAC \NWC"1;
"S \NAC"
BN"5"79;
%"TAP"
"1","(-2925,2400)","0","mstr_standard","I59";
;
HDL_TAP"TRUE"
BODY_TYPE"PLUMBING"
CDS_LIB"mstr_standard";
"B \NAC \NWC"1;
"S \NAC"
BN"3"81;
%"TAP"
"1","(-5250,1750)","2","mstr_standard","I6";
;
HDL_TAP"TRUE"
BODY_TYPE"PLUMBING"
CDS_LIB"mstr_standard";
"B \NAC \NWC"3;
"S \NAC"
BN"16"8;
%"TAP"
"1","(-2925,2350)","0","mstr_standard","I60";
;
HDL_TAP"TRUE"
BODY_TYPE"PLUMBING"
CDS_LIB"mstr_standard";
"B \NAC \NWC"1;
"S \NAC"
BN"4"80;
%"TAP"
"1","(-2925,2450)","0","mstr_standard","I61";
;
HDL_TAP"TRUE"
BODY_TYPE"PLUMBING"
CDS_LIB"mstr_standard";
"B \NAC \NWC"1;
"S \NAC"
BN"2"82;
%"TAP"
"1","(-2925,2500)","0","mstr_standard","I62";
;
HDL_TAP"TRUE"
BODY_TYPE"PLUMBING"
CDS_LIB"mstr_standard";
"B \NAC \NWC"1;
"S \NAC"
BN"1"83;
%"TAP"
"1","(-2925,2550)","0","mstr_standard","I63";
;
HDL_TAP"TRUE"
BODY_TYPE"PLUMBING"
CDS_LIB"mstr_standard";
"B \NAC \NWC"1;
"S \NAC"
BN"0"84;
%"TAP"
"1","(-2925,2650)","0","mstr_standard","I64";
;
HDL_TAP"TRUE"
BODY_TYPE"PLUMBING"
CDS_LIB"mstr_standard";
"B \NAC \NWC"2;
"S \NAC"
BN"19"54;
%"TAP"
"1","(-2925,2750)","0","mstr_standard","I65";
;
HDL_TAP"TRUE"
BODY_TYPE"PLUMBING"
CDS_LIB"mstr_standard";
"B \NAC \NWC"2;
"S \NAC"
BN"17"56;
%"TAP"
"1","(-2925,2700)","0","mstr_standard","I66";
;
HDL_TAP"TRUE"
BODY_TYPE"PLUMBING"
CDS_LIB"mstr_standard";
"B \NAC \NWC"2;
"S \NAC"
BN"18"55;
%"TAP"
"1","(-2925,2800)","0","mstr_standard","I67";
;
HDL_TAP"TRUE"
BODY_TYPE"PLUMBING"
CDS_LIB"mstr_standard";
"B \NAC \NWC"2;
"S \NAC"
BN"16"57;
%"TAP"
"1","(-2925,2850)","0","mstr_standard","I68";
;
HDL_TAP"TRUE"
BODY_TYPE"PLUMBING"
CDS_LIB"mstr_standard";
"B \NAC \NWC"2;
"S \NAC"
BN"15"58;
%"TAP"
"1","(-2925,2900)","0","mstr_standard","I69";
;
HDL_TAP"TRUE"
BODY_TYPE"PLUMBING"
CDS_LIB"mstr_standard";
"B \NAC \NWC"2;
"S \NAC"
BN"14"59;
%"TAP"
"1","(-5250,1800)","2","mstr_standard","I7";
;
HDL_TAP"TRUE"
BODY_TYPE"PLUMBING"
CDS_LIB"mstr_standard";
"B \NAC \NWC"3;
"S \NAC"
BN"15"9;
%"TAP"
"1","(-2925,3000)","0","mstr_standard","I70";
;
HDL_TAP"TRUE"
BODY_TYPE"PLUMBING"
CDS_LIB"mstr_standard";
"B \NAC \NWC"2;
"S \NAC"
BN"12"61;
%"TAP"
"1","(-2925,2950)","0","mstr_standard","I71";
;
HDL_TAP"TRUE"
BODY_TYPE"PLUMBING"
CDS_LIB"mstr_standard";
"B \NAC \NWC"2;
"S \NAC"
BN"13"60;
%"TAP"
"1","(-2925,3050)","0","mstr_standard","I72";
;
HDL_TAP"TRUE"
BODY_TYPE"PLUMBING"
CDS_LIB"mstr_standard";
"B \NAC \NWC"2;
"S \NAC"
BN"11"62;
%"TAP"
"1","(-2925,3100)","0","mstr_standard","I73";
;
HDL_TAP"TRUE"
BODY_TYPE"PLUMBING"
CDS_LIB"mstr_standard";
"B \NAC \NWC"2;
"S \NAC"
BN"10"63;
%"TAP"
"1","(-2925,3150)","0","mstr_standard","I74";
;
HDL_TAP"TRUE"
BODY_TYPE"PLUMBING"
CDS_LIB"mstr_standard";
"B \NAC \NWC"2;
"S \NAC"
BN"9"64;
%"TAP"
"1","(-2925,3250)","0","mstr_standard","I75";
;
HDL_TAP"TRUE"
BODY_TYPE"PLUMBING"
CDS_LIB"mstr_standard";
"B \NAC \NWC"2;
"S \NAC"
BN"7"66;
%"TAP"
"1","(-2925,3300)","0","mstr_standard","I76";
;
HDL_TAP"TRUE"
BODY_TYPE"PLUMBING"
CDS_LIB"mstr_standard";
"B \NAC \NWC"2;
"S \NAC"
BN"6"67;
%"TAP"
"1","(-2925,3200)","0","mstr_standard","I77";
;
HDL_TAP"TRUE"
BODY_TYPE"PLUMBING"
CDS_LIB"mstr_standard";
"B \NAC \NWC"2;
"S \NAC"
BN"8"65;
%"TAP"
"1","(-2925,3350)","0","mstr_standard","I78";
;
HDL_TAP"TRUE"
BODY_TYPE"PLUMBING"
CDS_LIB"mstr_standard";
"B \NAC \NWC"2;
"S \NAC"
BN"5"68;
%"TAP"
"1","(-2925,3400)","0","mstr_standard","I79";
;
HDL_TAP"TRUE"
BODY_TYPE"PLUMBING"
CDS_LIB"mstr_standard";
"B \NAC \NWC"2;
"S \NAC"
BN"4"69;
%"TAP"
"1","(-5250,1850)","2","mstr_standard","I8";
;
HDL_TAP"TRUE"
BODY_TYPE"PLUMBING"
CDS_LIB"mstr_standard";
"B \NAC \NWC"3;
"S \NAC"
BN"14"10;
%"TAP"
"1","(-2925,3550)","0","mstr_standard","I80";
;
HDL_TAP"TRUE"
BODY_TYPE"PLUMBING"
CDS_LIB"mstr_standard";
"B \NAC \NWC"2;
"S \NAC"
BN"1"72;
%"TAP"
"1","(-2925,3500)","0","mstr_standard","I81";
;
HDL_TAP"TRUE"
BODY_TYPE"PLUMBING"
CDS_LIB"mstr_standard";
"B \NAC \NWC"2;
"S \NAC"
BN"2"71;
%"TAP"
"1","(-2925,3450)","0","mstr_standard","I82";
;
HDL_TAP"TRUE"
BODY_TYPE"PLUMBING"
CDS_LIB"mstr_standard";
"B \NAC \NWC"2;
"S \NAC"
BN"3"70;
%"TAP"
"1","(-2925,3600)","0","mstr_standard","I83";
;
HDL_TAP"TRUE"
BODY_TYPE"PLUMBING"
CDS_LIB"mstr_standard";
"B \NAC \NWC"2;
"S \NAC"
BN"0"73;
%"SKX_EXT_B"
"13","(-4075,2600)","0","chpset_lib","I86";
;
CDS_SEC"13"
ROOM"CPU0"
CDS_LOCATION"U5D1"
SEC"13"
SEC_TYPE"BGA1"
CDS_LIB"chpset_lib"
PACK_TYPE"BGA1"
MATERIAL"IC"
PART_NUMBER"TBD"
LOCATION"U5D1";
"UPI0_TX_DP<0>"
$PN"M1"54;
"UPI0_TX_DP<1>"
$PN"T1"55;
"UPI0_TX_DP<2>"
$PN"Y3"56;
"UPI0_TX_DP<3>"
$PN"W2"57;
"UPI0_TX_DP<4>"
$PN"AA2"58;
"UPI0_TX_DP<5>"
$PN"AD1"59;
"UPI0_TX_DP<6>"
$PN"AF3"60;
"UPI0_TX_DP<7>"
$PN"AG2"61;
"UPI0_TX_DP<8>"
$PN"AJ2"62;
"UPI0_TX_DP<9>"
$PN"AK1"63;
"UPI0_TX_DP<10>"
$PN"AK3"64;
"UPI0_TX_DP<11>"
$PN"AP3"65;
"UPI0_TX_DP<12>"
$PN"AP1"66;
"UPI0_TX_DP<13>"
$PN"AR2"67;
"UPI0_TX_DP<14>"
$PN"AR4"68;
"UPI0_TX_DP<15>"
$PN"AW4"69;
"UPI0_TX_DP<16>"
$PN"AY3"70;
"UPI0_TX_DP<17>"
$PN"BC2"71;
"UPI0_TX_DP<18>"
$PN"BD3"72;
"UPI0_TX_DP<19>"
$PN"BH3"73;
"UPI0_TX_DN<0>"
$PN"N2"45;
"UPI0_TX_DN<1>"
$PN"P1"46;
"UPI0_TX_DN<2>"
$PN"V3"47;
"UPI0_TX_DN<3>"
$PN"Y1"48;
"UPI0_TX_DN<4>"
$PN"AB3"49;
"UPI0_TX_DN<5>"
$PN"AC2"50;
"UPI0_TX_DN<6>"
$PN"AG4"51;
"UPI0_TX_DN<7>"
$PN"AE2"52;
"UPI0_TX_DN<8>"
$PN"AH3"53;
"UPI0_TX_DN<9>"
$PN"AL2"74;
"UPI0_TX_DN<10>"
$PN"AM3"75;
"UPI0_TX_DN<11>"
$PN"AN4"76;
"UPI0_TX_DN<12>"
$PN"AT1"77;
"UPI0_TX_DN<13>"
$PN"AT3"78;
"UPI0_TX_DN<14>"
$PN"AU4"79;
"UPI0_TX_DN<15>"
$PN"AV5"80;
"UPI0_TX_DN<16>"
$PN"BA4"81;
"UPI0_TX_DN<17>"
$PN"BB3"82;
"UPI0_TX_DN<18>"
$PN"BF3"83;
"UPI0_TX_DN<19>"
$PN"BG4"84;
"UPI0_RX_DP<0>"
$PN"AB9"14;
"UPI0_RX_DP<1>"
$PN"AC8"15;
"UPI0_RX_DP<2>"
$PN"AA6"16;
"UPI0_RX_DP<3>"
$PN"AC6"17;
"UPI0_RX_DP<4>"
$PN"AG6"18;
"UPI0_RX_DP<5>"
$PN"AF7"19;
"UPI0_RX_DP<6>"
$PN"AH7"20;
"UPI0_RX_DP<7>"
$PN"AK5"21;
"UPI0_RX_DP<8>"
$PN"AM7"22;
"UPI0_RX_DP<9>"
$PN"AL8"23;
"UPI0_RX_DP<10>"
$PN"AN8"24;
"UPI0_RX_DP<11>"
$PN"AU8"25;
"UPI0_RX_DP<12>"
$PN"AT9"26;
"UPI0_RX_DP<13>"
$PN"AY7"27;
"UPI0_RX_DP<14>"
$PN"BB7"28;
"UPI0_RX_DP<15>"
$PN"BF7"29;
"UPI0_RX_DP<16>"
$PN"AV9"30;
"UPI0_RX_DP<17>"
$PN"BB9"31;
"UPI0_RX_DP<18>"
$PN"BC10"32;
"UPI0_RX_DP<19>"
$PN"BA10"33;
"UPI0_RX_DN<0>"
$PN"AC10"5;
"UPI0_RX_DN<1>"
$PN"AA8"6;
"UPI0_RX_DN<2>"
$PN"AB7"7;
"UPI0_RX_DN<3>"
$PN"AD5"8;
"UPI0_RX_DN<4>"
$PN"AE6"9;
"UPI0_RX_DN<5>"
$PN"AG8"10;
"UPI0_RX_DN<6>"
$PN"AJ6"11;
"UPI0_RX_DN<7>"
$PN"AL6"12;
"UPI0_RX_DN<8>"
$PN"AK7"13;
"UPI0_RX_DN<9>"
$PN"AM9"34;
"UPI0_RX_DN<10>"
$PN"AP7"35;
"UPI0_RX_DN<11>"
$PN"AR8"36;
"UPI0_RX_DN<12>"
$PN"AU10"37;
"UPI0_RX_DN<13>"
$PN"BA8"38;
"UPI0_RX_DN<14>"
$PN"BC6"39;
"UPI0_RX_DN<15>"
$PN"BD7"40;
"UPI0_RX_DN<16>"
$PN"AW8"41;
"UPI0_RX_DN<17>"
$PN"AY9"42;
"UPI0_RX_DN<18>"
$PN"BD9"43;
"UPI0_RX_DN<19>"
$PN"BB11"44;
%"TAP"
"1","(-5250,1950)","2","mstr_standard","I9";
;
HDL_TAP"TRUE"
BODY_TYPE"PLUMBING"
CDS_LIB"mstr_standard";
"B \NAC \NWC"3;
"S \NAC"
BN"12"12;
END.
